(kicad_pcb
	(version 20260206)
	(generator "pcbnew")
	(generator_version "10.0")
	(general
		(thickness 1.6)
		(legacy_teardrops no)
	)
	(paper "A4")
	(title_block
		(title "Wiwynn_Tioga_Pass_MB.brd")
		(comment 1 "Tioga Pass / footprints 3093-3099 of 4770")
	)
	(layers
		(0 "F.Cu" signal "TOP")
		(4 "In1.Cu" signal "L2GND")
		(6 "In2.Cu" signal "L3")
		(8 "In3.Cu" signal "L4GND")
		(10 "In4.Cu" signal "L5")
		(12 "In5.Cu" signal "L6GND")
		(14 "In6.Cu" signal "L7VCC")
		(16 "In7.Cu" signal "L8VCC")
		(18 "In8.Cu" signal "L9GND")
		(20 "In9.Cu" signal "L10")
		(22 "In10.Cu" signal "L11GND")
		(24 "In11.Cu" signal "L12")
		(26 "In12.Cu" signal "L13GND")
		(2 "B.Cu" signal "BOTTOM")
		(9 "F.Adhes" user "F.Adhesive")
		(11 "B.Adhes" user "B.Adhesive")
		(13 "F.Paste" user "Package Geometry/Pastemask Top")
		(15 "B.Paste" user "Package Geometry/Pastemask Bottom")
		(5 "F.SilkS" user "Ref Des/Silkscreen Top")
		(7 "B.SilkS" user "Ref Des/Silkscreen Bottom")
		(1 "F.Mask" user "Board Geometry/Soldermask Top")
		(3 "B.Mask" user "Board Geometry/Soldermask Bottom")
		(17 "Dwgs.User" user "User.Drawings")
		(19 "Cmts.User" user "User.Comments")
		(21 "Eco1.User" user "User.Eco1")
		(23 "Eco2.User" user "User.Eco2")
		(25 "Edge.Cuts" user "Board Geometry/Outline")
		(27 "Margin" user)
		(31 "F.CrtYd" user "Package Geometry/Place Bound Top")
		(29 "B.CrtYd" user "Package Geometry/Place Bound Bottom")
		(35 "F.Fab" user "Ref Des/Assembly Top")
		(33 "B.Fab" user "Ref Des/Assembly Bottom")
	)
	(footprint ""
		(layer "B.Cu")
		(at 385.774692 -44.215812)
		(property "Reference" "Q7E4"
			(at -0.22733 -3.73888 90)
			(unlocked yes)
			(layer "B.SilkS")
			(effects
				(font
					(size 0.7874 0.5842)
					(thickness 0.1524)
				)
				(justify left mirror)
			)
		)
		(property "Value" ""
			(at 0 0 0)
			(layer "B.Fab")
			(effects
				(font
					(size 1.27 1.27)
				)
				(justify mirror)
			)
		)
		(duplicate_pad_numbers_are_jumpers no)
		(fp_line
			(start -1.778 -0.5715)
			(end -1.778 0.3175)
			(stroke
				(width 0.1524)
				(type default)
			)
			(layer "B.SilkS")
		)
		(fp_line
			(start -1.778 2.4765)
			(end -1.778 1.5875)
			(stroke
				(width 0.1524)
				(type default)
			)
			(layer "B.SilkS")
		)
		(fp_line
			(start -0.9525 -0.5715)
			(end -1.778 -0.5715)
			(stroke
				(width 0.1524)
				(type default)
			)
			(layer "B.SilkS")
		)
		(fp_line
			(start -0.9525 2.4765)
			(end -1.778 2.4765)
			(stroke
				(width 0.1524)
				(type default)
			)
			(layer "B.SilkS")
		)
		(fp_line
			(start -0.381 0.635)
			(end -0.381 1.27)
			(stroke
				(width 0.1524)
				(type default)
			)
			(layer "B.SilkS")
		)
		(fp_circle
			(center 0.9525 -0.9271)
			(end 1.0795 -0.9271)
			(stroke
				(width 0.254)
				(type default)
			)
			(fill no)
			(layer "B.SilkS")
		)
		(fp_poly
			(pts
				(xy -1.778 2.4765) (xy -0.381 2.4765) (xy -0.381 -0.5715) (xy -1.778 -0.5715)
			)
			(stroke
				(width 0)
				(type default)
			)
			(fill no)
			(layer "B.CrtYd")
		)
		(fp_line
			(start -1.778 -0.5715)
			(end -0.381 -0.5715)
			(stroke
				(width 0.1)
				(type default)
			)
			(layer "B.Fab")
		)
		(fp_line
			(start -1.778 2.4765)
			(end -1.778 -0.5715)
			(stroke
				(width 0.1)
				(type default)
			)
			(layer "B.Fab")
		)
		(fp_line
			(start -0.381 -0.5715)
			(end -0.381 2.4765)
			(stroke
				(width 0.1)
				(type default)
			)
			(layer "B.Fab")
		)
		(fp_line
			(start -0.381 2.4765)
			(end -1.778 2.4765)
			(stroke
				(width 0.1)
				(type default)
			)
			(layer "B.Fab")
		)
		(fp_circle
			(center 0.9525 -0.9271)
			(end 1.0795 -0.9271)
			(stroke
				(width 0.254)
				(type default)
			)
			(fill no)
			(layer "B.Fab")
		)
		(pad "1" smd rect
			(at 0 0 180)
			(size 1.143 0.508)
			(layers "B.Cu" "B.Mask" "B.Paste")
			(net "FM_THROTTLE_R_N")
		)
		(pad "2" smd rect
			(at 0 1.905 180)
			(size 1.143 0.508)
			(layers "B.Cu" "B.Mask" "B.Paste")
			(net "GND")
		)
		(pad "3" smd rect
			(at -2.159 0.9525 180)
			(size 1.143 0.508)
			(layers "B.Cu" "B.Mask" "B.Paste")
			(net "FM_SYS_THROTTLE_LVC3")
		)
	)
	(footprint ""
		(layer "B.Cu")
		(at 342.9 -83.566)
		(property "Reference" "C3P6"
			(at 0 0 0)
			(layer "B.SilkS")
			(hide yes)
			(effects
				(font
					(size 1.27 1.27)
				)
				(justify mirror)
			)
		)
		(property "Value" ""
			(at 0 0 0)
			(layer "B.Fab")
			(effects
				(font
					(size 1.27 1.27)
				)
				(justify mirror)
			)
		)
		(duplicate_pad_numbers_are_jumpers no)
		(fp_poly
			(pts
				(xy -0.3048 -0.1016) (xy -0.3048 0.9906) (xy 0.3048 0.9906) (xy 0.3048 -0.1016)
			)
			(stroke
				(width 0)
				(type default)
			)
			(fill no)
			(layer "B.CrtYd")
		)
		(fp_line
			(start -0.3048 -0.1016)
			(end 0.3048 -0.1016)
			(stroke
				(width 0.1)
				(type default)
			)
			(layer "B.Fab")
		)
		(fp_line
			(start -0.3048 0.9906)
			(end -0.3048 -0.1016)
			(stroke
				(width 0.1)
				(type default)
			)
			(layer "B.Fab")
		)
		(fp_line
			(start 0.3048 -0.1016)
			(end 0.3048 0.9906)
			(stroke
				(width 0.1)
				(type default)
			)
			(layer "B.Fab")
		)
		(fp_line
			(start 0.3048 0.9906)
			(end -0.3048 0.9906)
			(stroke
				(width 0.1)
				(type default)
			)
			(layer "B.Fab")
		)
		(pad "1" smd rect
			(at 0 0 180)
			(size 0.508 0.508)
			(layers "B.Cu" "B.Mask" "B.Paste")
			(net "PWRGD_PVCCIO_CPU0_R")
		)
		(pad "2" smd rect
			(at 0 0.889 180)
			(size 0.508 0.508)
			(layers "B.Cu" "B.Mask" "B.Paste")
			(net "GND")
		)
		(zone
			(layer "B.Cu")
			(hatch none 0.5)
			(connect_pads
				(clearance 0)
			)
			(min_thickness 0.25)
			(keepout
				(tracks allowed)
				(vias not_allowed)
				(pads allowed)
				(copperpour not_allowed)
				(footprints allowed)
			)
			(placement
				(enabled no)
				(sheetname "")
			)
			(fill
				(thermal_gap 0.5)
				(thermal_bridge_width 0.5)
				(island_removal_mode 0)
			)
			(polygon
				(pts
					(xy 343.154 -83.312) (xy 342.646 -83.312) (xy 342.646 -82.931) (xy 343.154 -82.931)
				)
			)
		)
		(zone
			(layer "B.Cu")
			(hatch none 0.5)
			(connect_pads
				(clearance 0)
			)
			(min_thickness 0.25)
			(keepout
				(tracks not_allowed)
				(vias allowed)
				(pads allowed)
				(copperpour not_allowed)
				(footprints allowed)
			)
			(placement
				(enabled no)
				(sheetname "")
			)
			(fill
				(thermal_gap 0.5)
				(thermal_bridge_width 0.5)
				(island_removal_mode 0)
			)
			(polygon
				(pts
					(xy 343.154 -82.931) (xy 342.646 -82.931) (xy 342.646 -83.312) (xy 343.154 -83.312)
				)
			)
		)
	)
	(footprint ""
		(layer "B.Cu")
		(at 210.847432 -89.6112 -90)
		(property "Reference" "C6N9"
			(at -1.54813 -3.655568 0)
			(unlocked yes)
			(layer "B.SilkS")
			(effects
				(font
					(size 0.7874 0.5842)
					(thickness 0.1524)
				)
				(justify mirror)
			)
		)
		(property "Value" ""
			(at 0 0 90)
			(layer "B.Fab")
			(effects
				(font
					(size 1.27 1.27)
				)
				(justify mirror)
			)
		)
		(duplicate_pad_numbers_are_jumpers no)
		(fp_line
			(start -2.286 7.366)
			(end -1.600708 7.366)
			(stroke
				(width 0.1524)
				(type default)
			)
			(layer "B.SilkS")
		)
		(fp_line
			(start -2.286 7.366)
			(end -2.286 1.63195)
			(stroke
				(width 0.1524)
				(type default)
			)
			(layer "B.SilkS")
		)
		(fp_line
			(start 2.286 7.366)
			(end 1.60147 7.366)
			(stroke
				(width 0.1524)
				(type default)
			)
			(layer "B.SilkS")
		)
		(fp_line
			(start 2.286 7.366)
			(end 2.286 1.632712)
			(stroke
				(width 0.1524)
				(type default)
			)
			(layer "B.SilkS")
		)
		(fp_line
			(start -2.504948 1.633728)
			(end -1.6002 1.633728)
			(stroke
				(width 0.1524)
				(type default)
			)
			(layer "B.SilkS")
		)
		(fp_line
			(start 2.563114 1.633728)
			(end 1.6002 1.633728)
			(stroke
				(width 0.1524)
				(type default)
			)
			(layer "B.SilkS")
		)
		(fp_line
			(start -2.504948 -1.616456)
			(end -2.504948 1.633728)
			(stroke
				(width 0.1524)
				(type default)
			)
			(layer "B.SilkS")
		)
		(fp_line
			(start -1.6002 -1.616456)
			(end -2.504948 -1.616456)
			(stroke
				(width 0.1524)
				(type default)
			)
			(layer "B.SilkS")
		)
		(fp_line
			(start 1.6002 -1.616456)
			(end 2.563114 -1.616456)
			(stroke
				(width 0.1524)
				(type default)
			)
			(layer "B.SilkS")
		)
		(fp_line
			(start 2.563114 -1.616456)
			(end 2.563114 1.633728)
			(stroke
				(width 0.1524)
				(type default)
			)
			(layer "B.SilkS")
		)
		(fp_rect
			(start 2.286 7.366)
			(end -2.286 -0.254)
			(stroke
				(width 0)
				(type default)
			)
			(fill no)
			(layer "B.CrtYd")
		)
		(fp_line
			(start -2.286 7.366)
			(end 2.286 7.366)
			(stroke
				(width 0.1)
				(type default)
			)
			(layer "B.Fab")
		)
		(fp_line
			(start 2.286 7.366)
			(end 2.286 -0.254)
			(stroke
				(width 0.1)
				(type default)
			)
			(layer "B.Fab")
		)
		(fp_line
			(start -2.286 -0.254)
			(end -2.286 7.366)
			(stroke
				(width 0.1)
				(type default)
			)
			(layer "B.Fab")
		)
		(fp_line
			(start 2.286 -0.254)
			(end -2.286 -0.254)
			(stroke
				(width 0.1)
				(type default)
			)
			(layer "B.Fab")
		)
		(pad "1" smd rect
			(at 0 0 90)
			(size 2.54 3.048)
			(layers "B.Cu" "B.Mask" "B.Paste")
			(net "PVCCIN_CPU0")
		)
		(pad "2" smd rect
			(at 0 7.112 90)
			(size 2.54 3.048)
			(layers "B.Cu" "B.Mask" "B.Paste")
			(net "GND")
		)
	)
	(footprint ""
		(layer "B.Cu")
		(at 362.229654 -141.84249 -90)
		(property "Reference" "CF17"
			(at 0 0 90)
			(layer "B.SilkS")
			(hide yes)
			(effects
				(font
					(size 1.27 1.27)
				)
				(justify mirror)
			)
		)
		(property "Value" "*"
			(at -1.1811 -2.8194 270)
			(unlocked yes)
			(layer "B.Fab")
			(hide yes)
			(effects
				(font
					(size 1.27 1.016)
					(thickness 0.1524)
				)
				(justify mirror)
			)
		)
		(property "Device Type" "SC22P50V2JN-4GP_SMD-BCG-SC22P5A"
			(at -1.1811 -4.3434 270)
			(unlocked yes)
			(layer "B.Fab")
			(hide yes)
			(effects
				(font
					(size 1.27 1.016)
					(thickness 0.1524)
				)
				(justify mirror)
			)
		)
		(duplicate_pad_numbers_are_jumpers no)
		(fp_rect
			(start 0.4318 0.9525)
			(end -0.4318 -0.9525)
			(stroke
				(width 0)
				(type default)
			)
			(fill no)
			(layer "B.CrtYd")
		)
		(fp_rect
			(start 0.4318 0.9525)
			(end -0.4318 -0.9525)
			(stroke
				(width 0)
				(type default)
			)
			(fill no)
			(layer "B.Fab")
		)
		(pad "1" smd custom
			(at 0 -0.4445 90)
			(size 0.1524 0.1524)
			(layers "B.Cu" "B.Mask" "B.Paste")
			(net "VR_PVDDQ_DEF_AIREF1")
			(options
				(clearance outline)
				(anchor circle)
			)
			(primitives
				(gr_poly
					(pts
						(arc
							(start 0.3048 0.2032)
							(mid 0.275042 0.275042)
							(end 0.2032 0.3048)
						)
						(arc
							(start -0.2032 0.3048)
							(mid -0.275042 0.275042)
							(end -0.3048 0.2032)
						)
						(arc
							(start -0.3048 -0.2032)
							(mid -0.275042 -0.275042)
							(end -0.2032 -0.3048)
						)
						(arc
							(start 0.2032 -0.3048)
							(mid 0.275042 -0.275042)
							(end 0.3048 -0.2032)
						)
					)
					(width 0)
					(fill yes)
				)
			)
		)
		(pad "2" smd custom
			(at 0 0.4445 90)
			(size 0.1524 0.1524)
			(layers "B.Cu" "B.Mask" "B.Paste")
			(net "ISENSE_PVDDQ_DEF_PH1_IMON")
			(options
				(clearance outline)
				(anchor circle)
			)
			(primitives
				(gr_poly
					(pts
						(arc
							(start 0.3048 0.2032)
							(mid 0.275042 0.275042)
							(end 0.2032 0.3048)
						)
						(arc
							(start -0.2032 0.3048)
							(mid -0.275042 0.275042)
							(end -0.3048 0.2032)
						)
						(arc
							(start -0.3048 -0.2032)
							(mid -0.275042 -0.275042)
							(end -0.2032 -0.3048)
						)
						(arc
							(start 0.2032 -0.3048)
							(mid 0.275042 -0.275042)
							(end 0.3048 -0.2032)
						)
					)
					(width 0)
					(fill yes)
				)
			)
		)
	)
	(footprint ""
		(layer "B.Cu")
		(at 491.9345 -40.0304 -90)
		(property "Reference" "R1T1"
			(at 0 0 90)
			(layer "B.SilkS")
			(hide yes)
			(effects
				(font
					(size 1.27 1.27)
				)
				(justify mirror)
			)
		)
		(property "Value" ""
			(at 0 0 90)
			(layer "B.Fab")
			(effects
				(font
					(size 1.27 1.27)
				)
				(justify mirror)
			)
		)
		(duplicate_pad_numbers_are_jumpers no)
		(fp_poly
			(pts
				(xy 0.2794 -0.1016) (xy -0.2794 -0.1016) (xy -0.2794 0.9906) (xy 0.2794 0.9906)
			)
			(stroke
				(width 0)
				(type default)
			)
			(fill no)
			(layer "B.CrtYd")
		)
		(fp_line
			(start -0.2794 0.9906)
			(end -0.2794 -0.1016)
			(stroke
				(width 0.1)
				(type default)
			)
			(layer "B.Fab")
		)
		(fp_line
			(start 0.2794 0.9906)
			(end -0.2794 0.9906)
			(stroke
				(width 0.1)
				(type default)
			)
			(layer "B.Fab")
		)
		(fp_line
			(start -0.2794 -0.1016)
			(end 0.2794 -0.1016)
			(stroke
				(width 0.1)
				(type default)
			)
			(layer "B.Fab")
		)
		(fp_line
			(start 0.2794 -0.1016)
			(end 0.2794 0.9906)
			(stroke
				(width 0.1)
				(type default)
			)
			(layer "B.Fab")
		)
		(pad "1" smd rect
			(at 0 0 90)
			(size 0.508 0.508)
			(layers "B.Cu" "B.Mask" "B.Paste")
			(net "RMII_BMC_PCH_SPRNGVLLE_CRSDV")
		)
		(pad "2" smd rect
			(at 0 0.889 90)
			(size 0.508 0.508)
			(layers "B.Cu" "B.Mask" "B.Paste")
			(net "GND")
		)
		(zone
			(layer "B.Cu")
			(hatch none 0.5)
			(connect_pads
				(clearance 0)
			)
			(min_thickness 0.25)
			(keepout
				(tracks not_allowed)
				(vias allowed)
				(pads allowed)
				(copperpour not_allowed)
				(footprints allowed)
			)
			(placement
				(enabled no)
				(sheetname "")
			)
			(fill
				(thermal_gap 0.5)
				(thermal_bridge_width 0.5)
				(island_removal_mode 0)
			)
			(polygon
				(pts
					(xy 491.2995 -39.7764) (xy 491.2995 -40.2844) (xy 491.6805 -40.2844) (xy 491.6805 -39.7764)
				)
			)
		)
		(zone
			(layer "B.Cu")
			(hatch none 0.5)
			(connect_pads
				(clearance 0)
			)
			(min_thickness 0.25)
			(keepout
				(tracks allowed)
				(vias not_allowed)
				(pads allowed)
				(copperpour not_allowed)
				(footprints allowed)
			)
			(placement
				(enabled no)
				(sheetname "")
			)
			(fill
				(thermal_gap 0.5)
				(thermal_bridge_width 0.5)
				(island_removal_mode 0)
			)
			(polygon
				(pts
					(xy 491.6805 -39.7764) (xy 491.6805 -40.2844) (xy 491.2995 -40.2844) (xy 491.2995 -39.7764)
				)
			)
		)
	)
	(footprint ""
		(layer "B.Cu")
		(at 331.0255 -61.341 -90)
		(property "Reference" "R3P60"
			(at 0 0 90)
			(layer "B.SilkS")
			(hide yes)
			(effects
				(font
					(size 1.27 1.27)
				)
				(justify mirror)
			)
		)
		(property "Value" ""
			(at 0 0 90)
			(layer "B.Fab")
			(effects
				(font
					(size 1.27 1.27)
				)
				(justify mirror)
			)
		)
		(duplicate_pad_numbers_are_jumpers no)
		(fp_poly
			(pts
				(xy 0.2794 -0.1016) (xy -0.2794 -0.1016) (xy -0.2794 0.9906) (xy 0.2794 0.9906)
			)
			(stroke
				(width 0)
				(type default)
			)
			(fill no)
			(layer "B.CrtYd")
		)
		(fp_line
			(start -0.2794 0.9906)
			(end -0.2794 -0.1016)
			(stroke
				(width 0.1)
				(type default)
			)
			(layer "B.Fab")
		)
		(fp_line
			(start 0.2794 0.9906)
			(end -0.2794 0.9906)
			(stroke
				(width 0.1)
				(type default)
			)
			(layer "B.Fab")
		)
		(fp_line
			(start -0.2794 -0.1016)
			(end 0.2794 -0.1016)
			(stroke
				(width 0.1)
				(type default)
			)
			(layer "B.Fab")
		)
		(fp_line
			(start 0.2794 -0.1016)
			(end 0.2794 0.9906)
			(stroke
				(width 0.1)
				(type default)
			)
			(layer "B.Fab")
		)
		(pad "1" smd rect
			(at 0 0 90)
			(size 0.508 0.508)
			(layers "B.Cu" "B.Mask" "B.Paste")
			(net "PVCCIO_CPU0")
		)
		(pad "2" smd rect
			(at 0 0.889 90)
			(size 0.508 0.508)
			(layers "B.Cu" "B.Mask" "B.Paste")
			(net "SMB_DDR_DEF_SCL_G")
		)
		(zone
			(layer "B.Cu")
			(hatch none 0.5)
			(connect_pads
				(clearance 0)
			)
			(min_thickness 0.25)
			(keepout
				(tracks not_allowed)
				(vias allowed)
				(pads allowed)
				(copperpour not_allowed)
				(footprints allowed)
			)
			(placement
				(enabled no)
				(sheetname "")
			)
			(fill
				(thermal_gap 0.5)
				(thermal_bridge_width 0.5)
				(island_removal_mode 0)
			)
			(polygon
				(pts
					(xy 330.3905 -61.087) (xy 330.3905 -61.595) (xy 330.7715 -61.595) (xy 330.7715 -61.087)
				)
			)
		)
		(zone
			(layer "B.Cu")
			(hatch none 0.5)
			(connect_pads
				(clearance 0)
			)
			(min_thickness 0.25)
			(keepout
				(tracks allowed)
				(vias not_allowed)
				(pads allowed)
				(copperpour not_allowed)
				(footprints allowed)
			)
			(placement
				(enabled no)
				(sheetname "")
			)
			(fill
				(thermal_gap 0.5)
				(thermal_bridge_width 0.5)
				(island_removal_mode 0)
			)
			(polygon
				(pts
					(xy 330.7715 -61.087) (xy 330.7715 -61.595) (xy 330.3905 -61.595) (xy 330.3905 -61.087)
				)
			)
		)
	)
	(footprint ""
		(layer "B.Cu")
		(at 17.9832 -14.3002 -90)
		(property "Reference" "C9U2"
			(at -1.87833 9.144 0)
			(unlocked yes)
			(layer "B.SilkS")
			(effects
				(font
					(size 0.7874 0.5842)
					(thickness 0.1524)
				)
				(justify mirror)
			)
		)
		(property "Value" ""
			(at 0 0 90)
			(layer "B.Fab")
			(effects
				(font
					(size 1.27 1.27)
				)
				(justify mirror)
			)
		)
		(duplicate_pad_numbers_are_jumpers no)
		(fp_line
			(start -2.286 7.366)
			(end -1.600708 7.366)
			(stroke
				(width 0.1524)
				(type default)
			)
			(layer "B.SilkS")
		)
		(fp_line
			(start -2.286 7.366)
			(end -2.286 1.63195)
			(stroke
				(width 0.1524)
				(type default)
			)
			(layer "B.SilkS")
		)
		(fp_line
			(start 2.286 7.366)
			(end 1.60147 7.366)
			(stroke
				(width 0.1524)
				(type default)
			)
			(layer "B.SilkS")
		)
		(fp_line
			(start 2.286 7.366)
			(end 2.286 1.632712)
			(stroke
				(width 0.1524)
				(type default)
			)
			(layer "B.SilkS")
		)
		(fp_line
			(start -2.504948 1.633728)
			(end -1.6002 1.633728)
			(stroke
				(width 0.1524)
				(type default)
			)
			(layer "B.SilkS")
		)
		(fp_line
			(start 2.563114 1.633728)
			(end 1.6002 1.633728)
			(stroke
				(width 0.1524)
				(type default)
			)
			(layer "B.SilkS")
		)
		(fp_line
			(start -2.504948 -1.616456)
			(end -2.504948 1.633728)
			(stroke
				(width 0.1524)
				(type default)
			)
			(layer "B.SilkS")
		)
		(fp_line
			(start -1.6002 -1.616456)
			(end -2.504948 -1.616456)
			(stroke
				(width 0.1524)
				(type default)
			)
			(layer "B.SilkS")
		)
		(fp_line
			(start 1.6002 -1.616456)
			(end 2.563114 -1.616456)
			(stroke
				(width 0.1524)
				(type default)
			)
			(layer "B.SilkS")
		)
		(fp_line
			(start 2.563114 -1.616456)
			(end 2.563114 1.633728)
			(stroke
				(width 0.1524)
				(type default)
			)
			(layer "B.SilkS")
		)
		(fp_rect
			(start 2.286 -0.254)
			(end -2.286 7.366)
			(stroke
				(width 0)
				(type default)
			)
			(fill no)
			(layer "B.CrtYd")
		)
		(fp_line
			(start -2.286 7.366)
			(end 2.286 7.366)
			(stroke
				(width 0.1)
				(type default)
			)
			(layer "B.Fab")
		)
		(fp_line
			(start 2.286 7.366)
			(end 2.286 -0.254)
			(stroke
				(width 0.1)
				(type default)
			)
			(layer "B.Fab")
		)
		(fp_line
			(start -2.286 -0.254)
			(end -2.286 7.366)
			(stroke
				(width 0.1)
				(type default)
			)
			(layer "B.Fab")
		)
		(fp_line
			(start 2.286 -0.254)
			(end -2.286 -0.254)
			(stroke
				(width 0.1)
				(type default)
			)
			(layer "B.Fab")
		)
		(pad "1" smd rect
			(at 0 0 90)
			(size 2.54 3.048)
			(layers "B.Cu" "B.Mask" "B.Paste")
			(net "PVDDQ_GHJ")
		)
		(pad "2" smd rect
			(at 0 7.112 90)
			(size 2.54 3.048)
			(layers "B.Cu" "B.Mask" "B.Paste")
			(net "GND")
		)
	)
)
